# T6G (Grand Teton) — schematic netlist excerpt (pin names and nets, part order shuffled) for the footprints in the layout excerpt that follows; sources: Cadence DE-HDL packaged netlist, KiCad conversion of 04192023_DAF0TMB3IC0_F0TG_MB_C_brd_V02_OCP.brd

R954  Q_RES  11.5K 1% EMPTY  pkg 0402LF  page 169 : A = P3V3_AUX_DSC_VOL ; B = GND
C736  Q_CAP_DIFFBUS  DIFF BUS_0.22UF 6.3V 20% X6S  pkg C0201  page 66 : \1\ = P5E_CPU1_P1_TX_C_DN<2> ; \2\ = P5E_CPU1_P1_TX_DN<2>
PC349_3  Q_CAP  1UF 25V 10% X6S  pkg C0402  page 216 : A = SW_P12V_AUX_PVDDCR_SOC_P1_FLT ; B = GND

(kicad_pcb
	(version 20260206)
	(generator "pcbnew")
	(generator_version "10.0")
	(general
		(thickness 1.6)
		(legacy_teardrops no)
	)
	(paper "A4")
	(title_block
		(title "04192023_DAF0TMB3IC0_F0TG_MB_C_brd_V02_OCP.brd")
		(comment 1 "Grand Teton / footprints 1032-1034 of 8354")
	)
	(layers
		(0 "F.Cu" signal "TOP")
		(4 "In1.Cu" signal "GND")
		(6 "In2.Cu" signal "IN1")
		(8 "In3.Cu" signal "GND1")
		(10 "In4.Cu" signal "IN2")
		(12 "In5.Cu" signal "GND2")
		(14 "In6.Cu" signal "IN3")
		(16 "In7.Cu" signal "GND3")
		(18 "In8.Cu" signal "VCC")
		(20 "In9.Cu" signal "VCC1")
		(22 "In10.Cu" signal "GND4")
		(24 "In11.Cu" signal "IN4")
		(26 "In12.Cu" signal "GND5")
		(28 "In13.Cu" signal "IN5")
		(30 "In14.Cu" signal "GND6")
		(32 "In15.Cu" signal "IN6")
		(34 "In16.Cu" signal "GND7")
		(2 "B.Cu" signal "BOTTOM")
		(9 "F.Adhes" user "F.Adhesive")
		(11 "B.Adhes" user "B.Adhesive")
		(13 "F.Paste" user "Package Geometry/Pastemask Top")
		(15 "B.Paste" user "Package Geometry/Pastemask Bottom")
		(5 "F.SilkS" user "Ref Des/Silkscreen Top")
		(7 "B.SilkS" user "Ref Des/Silkscreen Bottom")
		(1 "F.Mask" user "Board Geometry/Soldermask Top")
		(3 "B.Mask" user "Board Geometry/Soldermask Bottom")
		(17 "Dwgs.User" user "User.Drawings")
		(19 "Cmts.User" user "User.Comments")
		(21 "Eco1.User" user "User.Eco1")
		(23 "Eco2.User" user "User.Eco2")
		(25 "Edge.Cuts" user "Board Geometry/Outline")
		(27 "Margin" user)
		(31 "F.CrtYd" user "Package Geometry/Place Bound Top")
		(29 "B.CrtYd" user "Package Geometry/Place Bound Bottom")
		(35 "F.Fab" user "Ref Des/Assembly Top")
		(33 "B.Fab" user "Ref Des/Assembly Bottom")
	)
	(footprint ""
		(layer "F.Cu")
		(at 76.431902 -373.03583 -90)
		(property "Reference" "C736"
			(at 0 0 270)
			(layer "F.SilkS")
			(hide yes)
			(effects
				(font
					(size 1.27 1.27)
				)
			)
		)
		(property "Value" ""
			(at 0 0 270)
			(layer "F.Fab")
			(effects
				(font
					(size 1.27 1.27)
				)
			)
		)
		(duplicate_pad_numbers_are_jumpers no)
		(fp_line
			(start -0.299974 0.150114)
			(end -0.299974 -0.150114)
			(stroke
				(width 0.1)
				(type default)
			)
			(layer "F.Fab")
		)
		(fp_line
			(start 0.299974 0.150114)
			(end -0.299974 0.150114)
			(stroke
				(width 0.1)
				(type default)
			)
			(layer "F.Fab")
		)
		(fp_line
			(start -0.299974 -0.150114)
			(end 0.299974 -0.150114)
			(stroke
				(width 0.1)
				(type default)
			)
			(layer "F.Fab")
		)
		(fp_line
			(start 0.299974 -0.150114)
			(end 0.299974 0.150114)
			(stroke
				(width 0.1)
				(type default)
			)
			(layer "F.Fab")
		)
		(pad "1" smd rect
			(at -0.2667 0 270)
			(size 0.3048 0.381)
			(layers "F.Cu" "F.Mask" "F.Paste")
			(net "P5E_CPU1_P1_TX_C_DN<2>")
		)
		(pad "2" smd rect
			(at 0.2667 0 270)
			(size 0.3048 0.381)
			(layers "F.Cu" "F.Mask" "F.Paste")
			(net "P5E_CPU1_P1_TX_DN<2>")
		)
	)
	(footprint ""
		(layer "F.Cu")
		(at 48.11014 -99.60864 -90)
		(property "Reference" "R954"
			(at 0 0 270)
			(layer "F.SilkS")
			(hide yes)
			(effects
				(font
					(size 1.27 1.27)
				)
			)
		)
		(property "Value" ""
			(at 0 0 270)
			(layer "F.Fab")
			(effects
				(font
					(size 1.27 1.27)
				)
			)
		)
		(duplicate_pad_numbers_are_jumpers no)
		(fp_line
			(start -0.7874 0.4064)
			(end -0.7874 -0.4064)
			(stroke
				(width 0.1524)
				(type default)
			)
			(layer "F.SilkS")
		)
		(fp_line
			(start 0.7874 0.4064)
			(end -0.7874 0.4064)
			(stroke
				(width 0.1524)
				(type default)
			)
			(layer "F.SilkS")
		)
		(fp_line
			(start -0.7874 -0.4064)
			(end 0.7874 -0.4064)
			(stroke
				(width 0.1524)
				(type default)
			)
			(layer "F.SilkS")
		)
		(fp_line
			(start 0.7874 -0.4064)
			(end 0.7874 0.4064)
			(stroke
				(width 0.1524)
				(type default)
			)
			(layer "F.SilkS")
		)
		(fp_line
			(start -0.67945 0.3048)
			(end -0.67945 -0.305054)
			(stroke
				(width 0.1)
				(type default)
			)
			(layer "F.Fab")
		)
		(fp_line
			(start -0.12065 0.3048)
			(end -0.67945 0.3048)
			(stroke
				(width 0.1)
				(type default)
			)
			(layer "F.Fab")
		)
		(fp_line
			(start 0.120396 0.3048)
			(end 0.120396 0.2794)
			(stroke
				(width 0.1)
				(type default)
			)
			(layer "F.Fab")
		)
		(fp_line
			(start 0.67945 0.3048)
			(end 0.120396 0.3048)
			(stroke
				(width 0.1)
				(type default)
			)
			(layer "F.Fab")
		)
		(fp_line
			(start -0.12065 0.2794)
			(end -0.12065 0.3048)
			(stroke
				(width 0.1)
				(type default)
			)
			(layer "F.Fab")
		)
		(fp_line
			(start 0.120396 0.2794)
			(end -0.12065 0.2794)
			(stroke
				(width 0.1)
				(type default)
			)
			(layer "F.Fab")
		)
		(fp_line
			(start -0.12065 -0.2794)
			(end 0.12065 -0.2794)
			(stroke
				(width 0.1)
				(type default)
			)
			(layer "F.Fab")
		)
		(fp_line
			(start 0.12065 -0.2794)
			(end 0.12065 -0.3048)
			(stroke
				(width 0.1)
				(type default)
			)
			(layer "F.Fab")
		)
		(fp_line
			(start 0.12065 -0.3048)
			(end 0.67945 -0.3048)
			(stroke
				(width 0.1)
				(type default)
			)
			(layer "F.Fab")
		)
		(fp_line
			(start 0.67945 -0.3048)
			(end 0.67945 0.3048)
			(stroke
				(width 0.1)
				(type default)
			)
			(layer "F.Fab")
		)
		(fp_line
			(start -0.67945 -0.305054)
			(end -0.12065 -0.305054)
			(stroke
				(width 0.1)
				(type default)
			)
			(layer "F.Fab")
		)
		(fp_line
			(start -0.12065 -0.305054)
			(end -0.12065 -0.2794)
			(stroke
				(width 0.1)
				(type default)
			)
			(layer "F.Fab")
		)
		(pad "1" smd circle
			(at -0.40005 0 270)
			(size 0 0)
			(layers "F.Cu" "F.Mask" "F.Paste")
			(net "P3V3_AUX_DSC_VOL")
		)
		(pad "2" smd circle
			(at 0.40005 0 270)
			(size 0 0)
			(layers "F.Cu" "F.Mask" "F.Paste")
			(net "GND")
		)
	)
	(footprint ""
		(layer "F.Cu")
		(at 128.768856 -156.443934 90)
		(property "Reference" "PC349_3"
			(at 0 0 90)
			(layer "F.SilkS")
			(hide yes)
			(effects
				(font
					(size 1.27 1.27)
				)
			)
		)
		(property "Value" ""
			(at 0 0 90)
			(layer "F.Fab")
			(effects
				(font
					(size 1.27 1.27)
				)
			)
		)
		(duplicate_pad_numbers_are_jumpers no)
		(fp_line
			(start 0.7874 -0.4064)
			(end 0.7874 0.4064)
			(stroke
				(width 0.1524)
				(type default)
			)
			(layer "F.SilkS")
		)
		(fp_line
			(start -0.7874 -0.4064)
			(end 0.7874 -0.4064)
			(stroke
				(width 0.1524)
				(type default)
			)
			(layer "F.SilkS")
		)
		(fp_line
			(start 0.7874 0.4064)
			(end -0.7874 0.4064)
			(stroke
				(width 0.1524)
				(type default)
			)
			(layer "F.SilkS")
		)
		(fp_line
			(start -0.7874 0.4064)
			(end -0.7874 -0.4064)
			(stroke
				(width 0.1524)
				(type default)
			)
			(layer "F.SilkS")
		)
		(fp_line
			(start -0.12065 -0.305054)
			(end -0.12065 -0.2794)
			(stroke
				(width 0.1)
				(type default)
			)
			(layer "F.Fab")
		)
		(fp_line
			(start -0.67945 -0.305054)
			(end -0.12065 -0.305054)
			(stroke
				(width 0.1)
				(type default)
			)
			(layer "F.Fab")
		)
		(fp_line
			(start 0.67945 -0.3048)
			(end 0.67945 0.3048)
			(stroke
				(width 0.1)
				(type default)
			)
			(layer "F.Fab")
		)
		(fp_line
			(start 0.12065 -0.3048)
			(end 0.67945 -0.3048)
			(stroke
				(width 0.1)
				(type default)
			)
			(layer "F.Fab")
		)
		(fp_line
			(start 0.12065 -0.2794)
			(end 0.12065 -0.3048)
			(stroke
				(width 0.1)
				(type default)
			)
			(layer "F.Fab")
		)
		(fp_line
			(start -0.12065 -0.2794)
			(end 0.12065 -0.2794)
			(stroke
				(width 0.1)
				(type default)
			)
			(layer "F.Fab")
		)
		(fp_line
			(start 0.120396 0.2794)
			(end -0.12065 0.2794)
			(stroke
				(width 0.1)
				(type default)
			)
			(layer "F.Fab")
		)
		(fp_line
			(start -0.12065 0.2794)
			(end -0.12065 0.3048)
			(stroke
				(width 0.1)
				(type default)
			)
			(layer "F.Fab")
		)
		(fp_line
			(start 0.67945 0.3048)
			(end 0.120396 0.3048)
			(stroke
				(width 0.1)
				(type default)
			)
			(layer "F.Fab")
		)
		(fp_line
			(start 0.120396 0.3048)
			(end 0.120396 0.2794)
			(stroke
				(width 0.1)
				(type default)
			)
			(layer "F.Fab")
		)
		(fp_line
			(start -0.12065 0.3048)
			(end -0.67945 0.3048)
			(stroke
				(width 0.1)
				(type default)
			)
			(layer "F.Fab")
		)
		(fp_line
			(start -0.67945 0.3048)
			(end -0.67945 -0.305054)
			(stroke
				(width 0.1)
				(type default)
			)
			(layer "F.Fab")
		)
		(pad "1" smd circle
			(at -0.40005 0 90)
			(size 0 0)
			(layers "F.Cu" "F.Mask" "F.Paste")
			(net "SW_P12V_AUX_PVDDCR_SOC_P1_FLT")
		)
		(pad "2" smd circle
			(at 0.40005 0 90)
			(size 0 0)
			(layers "F.Cu" "F.Mask" "F.Paste")
			(net "GND")
		)
	)
)
